(kicad_pcb
	(version 20260206)
	(generator "pcbnew")
	(generator_version "10.0")
	(general
		(thickness 1.6)
		(legacy_teardrops no)
	)
	(paper "A4")
	(title_block
		(title "v1-tray-backplane — T6M_tray_BP_c_1023_1120.brd")
		(comment 1 "Open CloudServer (Microsoft) / footprints 123-130 of 170")
	)
	(layers
		(0 "F.Cu" signal "TOP")
		(4 "In1.Cu" signal "GND")
		(6 "In2.Cu" signal "IN1")
		(8 "In3.Cu" signal "VCC")
		(10 "In4.Cu" signal "VCC1")
		(12 "In5.Cu" signal "IN2")
		(14 "In6.Cu" signal "GND1")
		(2 "B.Cu" signal "BOTTOM")
		(9 "F.Adhes" user "F.Adhesive")
		(11 "B.Adhes" user "B.Adhesive")
		(13 "F.Paste" user "Package Geometry/Pastemask Top")
		(15 "B.Paste" user "Package Geometry/Pastemask Bottom")
		(5 "F.SilkS" user "Ref Des/Silkscreen Top")
		(7 "B.SilkS" user "Ref Des/Silkscreen Bottom")
		(1 "F.Mask" user "Board Geometry/Soldermask Top")
		(3 "B.Mask" user "Board Geometry/Soldermask Bottom")
		(17 "Dwgs.User" user "User.Drawings")
		(19 "Cmts.User" user "User.Comments")
		(21 "Eco1.User" user "User.Eco1")
		(23 "Eco2.User" user "User.Eco2")
		(25 "Edge.Cuts" user "Board Geometry/Outline")
		(27 "Margin" user)
		(31 "F.CrtYd" user "Package Geometry/Place Bound Top")
		(29 "B.CrtYd" user "Package Geometry/Place Bound Bottom")
		(35 "F.Fab" user "Ref Des/Assembly Top")
		(33 "B.Fab" user "Ref Des/Assembly Bottom")
	)
	(footprint ""
		(layer "F.Cu")
		(at 3.578352 -20.360132 180)
		(property "Reference" "JP8"
			(at 2.686304 -3.612134 0)
			(unlocked yes)
			(layer "F.SilkS")
			(effects
				(font
					(size 0.7874 0.5842)
					(thickness 0.1524)
				)
				(justify left)
			)
		)
		(property "Value" ""
			(at 0 0 180)
			(layer "F.Fab")
			(effects
				(font
					(size 1.27 1.27)
				)
			)
		)
		(duplicate_pad_numbers_are_jumpers no)
		(fp_line
			(start 2.54 1.27)
			(end -2.54 1.27)
			(stroke
				(width 0.1524)
				(type default)
			)
			(layer "F.SilkS")
		)
		(fp_line
			(start 2.54 -1.27)
			(end 2.54 1.27)
			(stroke
				(width 0.1524)
				(type default)
			)
			(layer "F.SilkS")
		)
		(fp_line
			(start -2.54 1.27)
			(end -2.54 -1.27)
			(stroke
				(width 0.1524)
				(type default)
			)
			(layer "F.SilkS")
		)
		(fp_line
			(start -2.54 -1.27)
			(end 2.54 -1.27)
			(stroke
				(width 0.1524)
				(type default)
			)
			(layer "F.SilkS")
		)
		(fp_poly
			(pts
				(xy -2.78638 -0.799084) (xy -4.10718 -1.383284) (xy -4.10718 -0.164084)
			)
			(stroke
				(width 0)
				(type default)
			)
			(fill yes)
			(layer "F.SilkS")
		)
		(fp_poly
			(pts
				(xy -2.1082 -0.8382) (xy -2.1082 0.8382) (xy 2.1082 0.8382) (xy 2.1082 -0.8382)
			)
			(stroke
				(width 0)
				(type default)
			)
			(fill no)
			(layer "B.CrtYd")
		)
		(fp_rect
			(start -2.54 1.27)
			(end 2.54 -1.27)
			(stroke
				(width 0)
				(type default)
			)
			(fill no)
			(layer "F.CrtYd")
		)
		(fp_line
			(start 2.54 1.27)
			(end -2.54 1.27)
			(stroke
				(width 0.1)
				(type default)
			)
			(layer "F.Fab")
		)
		(fp_line
			(start 2.54 -1.27)
			(end 2.54 1.27)
			(stroke
				(width 0.1)
				(type default)
			)
			(layer "F.Fab")
		)
		(fp_line
			(start -2.54 1.27)
			(end -2.54 -1.27)
			(stroke
				(width 0.1)
				(type default)
			)
			(layer "F.Fab")
		)
		(fp_line
			(start -2.54 -1.27)
			(end 2.54 -1.27)
			(stroke
				(width 0.1)
				(type default)
			)
			(layer "F.Fab")
		)
		(fp_text user "2"
			(at 3.219704 -1.783334 0)
			(unlocked yes)
			(layer "F.SilkS")
			(effects
				(font
					(size 0.7874 0.5842)
					(thickness 0.1524)
				)
				(justify left)
			)
		)
		(fp_text user "1"
			(at -2.647696 0.070866 0)
			(unlocked yes)
			(layer "F.SilkS")
			(effects
				(font
					(size 0.7874 0.5842)
					(thickness 0.1524)
				)
				(justify left)
			)
		)
		(fp_text user "2"
			(at 2.406904 -0.005334 0)
			(unlocked yes)
			(layer "B.SilkS")
			(effects
				(font
					(size 0.7874 0.5842)
					(thickness 0.1524)
				)
				(justify left mirror)
			)
		)
		(fp_text user "1"
			(at -2.876296 -0.030734 0)
			(unlocked yes)
			(layer "B.SilkS")
			(effects
				(font
					(size 0.7874 0.5842)
					(thickness 0.1524)
				)
				(justify left mirror)
			)
		)
		(pad "1" thru_hole rect
			(at -1.27 0 180)
			(size 1.6764 1.6764)
			(drill 1.1684)
			(layers "*.Cu" "*.Mask")
			(remove_unused_layers no)
			(net "NODE3_EN")
			(clearance 0)
			(padstack
				(mode front_inner_back)
				(layer "Inner"
					(shape circle)
					(size 1.6764 1.6764)
					(clearance 0)
				)
				(layer "B.Cu"
					(shape rect)
					(size 1.6764 1.6764)
					(clearance 0)
				)
			)
		)
		(pad "2" thru_hole circle
			(at 1.27 0 180)
			(size 1.6764 1.6764)
			(drill 1.1684)
			(layers "*.Cu" "*.Mask")
			(remove_unused_layers no)
			(net "N39398095")
			(clearance 0)
		)
	)
	(footprint ""
		(layer "F.Cu")
		(at 310.308752 -27.523694 180)
		(property "Reference" "R52"
			(at 6.775704 1.30556 0)
			(unlocked yes)
			(layer "F.SilkS")
			(effects
				(font
					(size 0.7874 0.5842)
					(thickness 0.1524)
				)
				(justify left)
			)
		)
		(property "Value" ""
			(at 0 0 180)
			(layer "F.Fab")
			(effects
				(font
					(size 1.27 1.27)
				)
			)
		)
		(duplicate_pad_numbers_are_jumpers no)
		(fp_line
			(start 0.7874 0.4064)
			(end -0.7874 0.4064)
			(stroke
				(width 0.1524)
				(type default)
			)
			(layer "F.SilkS")
		)
		(fp_line
			(start 0.7874 -0.4064)
			(end 0.7874 0.4064)
			(stroke
				(width 0.1524)
				(type default)
			)
			(layer "F.SilkS")
		)
		(fp_line
			(start -0.7874 0.4064)
			(end -0.7874 -0.4064)
			(stroke
				(width 0.1524)
				(type default)
			)
			(layer "F.SilkS")
		)
		(fp_line
			(start -0.7874 -0.4064)
			(end 0.7874 -0.4064)
			(stroke
				(width 0.1524)
				(type default)
			)
			(layer "F.SilkS")
		)
		(fp_poly
			(pts
				(xy -0.508 0.2794) (xy -0.508 0.2286) (xy -0.635 0.2286) (xy -0.635 -0.254) (xy -0.5334 -0.254)
				(xy -0.5334 -0.2794) (xy 0.5334 -0.2794) (xy 0.5334 -0.254) (xy 0.635 -0.254) (xy 0.635 0.254) (xy 0.5334 0.254)
				(xy 0.5334 0.2794)
			)
			(stroke
				(width 0)
				(type default)
			)
			(fill no)
			(layer "F.CrtYd")
		)
		(pad "1" smd rect
			(at 0.40005 0 180)
			(size 0.4572 0.508)
			(layers "F.Cu" "F.Mask" "F.Paste")
			(net "GND")
		)
		(pad "2" smd rect
			(at -0.40005 0 180)
			(size 0.4572 0.508)
			(layers "F.Cu" "F.Mask" "F.Paste")
			(net "ENET10G_4_RS0")
		)
	)
	(footprint ""
		(layer "F.Cu")
		(at 130.101848 -25.440894 180)
		(property "Reference" "R7"
			(at 61.677296 -5.09524 0)
			(unlocked yes)
			(layer "F.SilkS")
			(effects
				(font
					(size 0.7874 0.5842)
					(thickness 0.1524)
				)
				(justify left)
			)
		)
		(property "Value" ""
			(at 0 0 180)
			(layer "F.Fab")
			(effects
				(font
					(size 1.27 1.27)
				)
			)
		)
		(duplicate_pad_numbers_are_jumpers no)
		(fp_line
			(start 0.7874 0.4064)
			(end -0.7874 0.4064)
			(stroke
				(width 0.1524)
				(type default)
			)
			(layer "F.SilkS")
		)
		(fp_line
			(start 0.7874 -0.4064)
			(end 0.7874 0.4064)
			(stroke
				(width 0.1524)
				(type default)
			)
			(layer "F.SilkS")
		)
		(fp_line
			(start -0.7874 0.4064)
			(end -0.7874 -0.4064)
			(stroke
				(width 0.1524)
				(type default)
			)
			(layer "F.SilkS")
		)
		(fp_line
			(start -0.7874 -0.4064)
			(end 0.7874 -0.4064)
			(stroke
				(width 0.1524)
				(type default)
			)
			(layer "F.SilkS")
		)
		(fp_poly
			(pts
				(xy -0.508 0.2794) (xy -0.508 0.2286) (xy -0.635 0.2286) (xy -0.635 -0.254) (xy -0.5334 -0.254)
				(xy -0.5334 -0.2794) (xy 0.5334 -0.2794) (xy 0.5334 -0.254) (xy 0.635 -0.254) (xy 0.635 0.254) (xy 0.5334 0.254)
				(xy 0.5334 0.2794)
			)
			(stroke
				(width 0)
				(type default)
			)
			(fill no)
			(layer "F.CrtYd")
		)
		(pad "1" smd rect
			(at 0.40005 0 180)
			(size 0.4572 0.508)
			(layers "F.Cu" "F.Mask" "F.Paste")
			(net "P3V3_BLAD1")
		)
		(pad "2" smd rect
			(at -0.40005 0 180)
			(size 0.4572 0.508)
			(layers "F.Cu" "F.Mask" "F.Paste")
			(net "ENET10G_1_SCL")
		)
	)
	(footprint ""
		(layer "F.Cu")
		(at 378.431552 -27.776678)
		(property "Reference" "R49"
			(at 33.4772 17.307052 0)
			(unlocked yes)
			(layer "F.SilkS")
			(effects
				(font
					(size 0.7874 0.5842)
					(thickness 0.1524)
				)
				(justify left)
			)
		)
		(property "Value" ""
			(at 0 0 0)
			(layer "F.Fab")
			(effects
				(font
					(size 1.27 1.27)
				)
			)
		)
		(duplicate_pad_numbers_are_jumpers no)
		(fp_line
			(start -0.7874 -0.4064)
			(end 0.7874 -0.4064)
			(stroke
				(width 0.1524)
				(type default)
			)
			(layer "F.SilkS")
		)
		(fp_line
			(start -0.7874 0.4064)
			(end -0.7874 -0.4064)
			(stroke
				(width 0.1524)
				(type default)
			)
			(layer "F.SilkS")
		)
		(fp_line
			(start 0.7874 -0.4064)
			(end 0.7874 0.4064)
			(stroke
				(width 0.1524)
				(type default)
			)
			(layer "F.SilkS")
		)
		(fp_line
			(start 0.7874 0.4064)
			(end -0.7874 0.4064)
			(stroke
				(width 0.1524)
				(type default)
			)
			(layer "F.SilkS")
		)
		(fp_poly
			(pts
				(xy -0.508 0.2794) (xy -0.508 0.2286) (xy -0.635 0.2286) (xy -0.635 -0.254) (xy -0.5334 -0.254)
				(xy -0.5334 -0.2794) (xy 0.5334 -0.2794) (xy 0.5334 -0.254) (xy 0.635 -0.254) (xy 0.635 0.254) (xy 0.5334 0.254)
				(xy 0.5334 0.2794)
			)
			(stroke
				(width 0)
				(type default)
			)
			(fill no)
			(layer "F.CrtYd")
		)
		(pad "1" smd rect
			(at 0.40005 0)
			(size 0.4572 0.508)
			(layers "F.Cu" "F.Mask" "F.Paste")
			(net "GND")
		)
		(pad "2" smd rect
			(at -0.40005 0)
			(size 0.4572 0.508)
			(layers "F.Cu" "F.Mask" "F.Paste")
			(net "ENET10G_3_RS1")
		)
	)
	(footprint ""
		(layer "F.Cu")
		(at 86.480142 -33.7312 90)
		(property "Reference" "L4"
			(at -0.5842 -3.668014 90)
			(unlocked yes)
			(layer "F.SilkS")
			(effects
				(font
					(size 0.7874 0.5842)
					(thickness 0.1524)
				)
				(justify left)
			)
		)
		(property "Value" ""
			(at 0 0 90)
			(layer "F.Fab")
			(effects
				(font
					(size 1.27 1.27)
				)
			)
		)
		(duplicate_pad_numbers_are_jumpers no)
		(fp_line
			(start -1.905 -0.8636)
			(end 1.905 -0.8636)
			(stroke
				(width 0.1524)
				(type default)
			)
			(layer "F.SilkS")
		)
		(fp_line
			(start 1.905 0.8382)
			(end 1.905 -0.8382)
			(stroke
				(width 0.1524)
				(type default)
			)
			(layer "F.SilkS")
		)
		(fp_line
			(start 0.127 0.8382)
			(end 0.127 -0.8382)
			(stroke
				(width 0.1524)
				(type default)
			)
			(layer "F.SilkS")
		)
		(fp_line
			(start -0.127 0.8382)
			(end -0.127 -0.8382)
			(stroke
				(width 0.1524)
				(type default)
			)
			(layer "F.SilkS")
		)
		(fp_line
			(start -1.905 0.8382)
			(end -1.905 -0.8382)
			(stroke
				(width 0.1524)
				(type default)
			)
			(layer "F.SilkS")
		)
		(fp_line
			(start 1.905 0.8636)
			(end -1.905 0.8636)
			(stroke
				(width 0.1524)
				(type default)
			)
			(layer "F.SilkS")
		)
		(fp_rect
			(start -1.524 0.7112)
			(end 1.524 -0.7366)
			(stroke
				(width 0)
				(type default)
			)
			(fill no)
			(layer "F.CrtYd")
		)
		(pad "1" smd rect
			(at 0.94996 0 90)
			(size 1.1176 1.3716)
			(layers "F.Cu" "F.Mask" "F.Paste")
			(net "P3V3_10G_2_VCCR_L")
		)
		(pad "2" smd rect
			(at -0.94996 0 90)
			(size 1.1176 1.3716)
			(layers "F.Cu" "F.Mask" "F.Paste")
			(net "P3V3_10G_2_VCCR")
		)
	)
	(footprint ""
		(layer "F.Cu")
		(at 279.81021 -4.700016 180)
		(property "Reference" "H2"
			(at 0.23622 11.596116 0)
			(unlocked yes)
			(layer "F.SilkS")
			(effects
				(font
					(size 0.7874 0.5842)
					(thickness 0.1524)
				)
				(justify left)
			)
		)
		(property "Value" ""
			(at 0 0 180)
			(layer "F.Fab")
			(effects
				(font
					(size 1.27 1.27)
				)
			)
		)
		(duplicate_pad_numbers_are_jumpers no)
		(fp_poly
			(pts
				(arc
					(start 3.999992 5.999988)
					(mid 0 9.99998)
					(end -3.999992 5.999988)
				)
				(arc
					(start -3.999992 0)
					(mid 0 -3.999992)
					(end 3.999992 0)
				)
			)
			(stroke
				(width 0)
				(type default)
			)
			(fill no)
			(layer "B.CrtYd")
		)
		(fp_poly
			(pts
				(arc
					(start 3.999992 5.999988)
					(mid 0 9.99998)
					(end -3.999992 5.999988)
				)
				(arc
					(start -3.999992 0)
					(mid 0 -3.999992)
					(end 3.999992 0)
				)
			)
			(stroke
				(width 0)
				(type default)
			)
			(fill no)
			(layer "F.CrtYd")
		)
		(pad "" np_thru_hole circle
			(at 0 0 180)
			(size 3.5052 3.5052)
			(drill 3.5052)
			(layers "*.Cu" "*.Mask")
			(clearance 0.381)
			(thermal_gap 0.381)
		)
		(zone
			(layers "F.Cu" "B.Cu" "In1.Cu" "In2.Cu" "In3.Cu" "In4.Cu" "In5.Cu" "In6.Cu")
			(hatch none 0.5)
			(connect_pads
				(clearance 0)
			)
			(min_thickness 0.25)
			(keepout
				(tracks not_allowed)
				(vias allowed)
				(pads allowed)
				(copperpour not_allowed)
				(footprints allowed)
			)
			(placement
				(enabled no)
				(sheetname "")
			)
			(fill
				(thermal_gap 0.5)
				(thermal_bridge_width 0.5)
				(island_removal_mode 0)
			)
			(polygon
				(pts
					(arc
						(start 277.39848 -8.152638)
						(mid 279.81021 -14.207926)
						(end 282.22194 -8.152638)
					)
					(arc
						(start 282.22194 -8.152638)
						(mid 282.108311 -7.989777)
						(end 282.06827 -7.79526)
					)
					(arc
						(start 282.06827 -4.700016)
						(mid 279.81021 -2.441956)
						(end 277.55215 -4.700016)
					)
					(arc
						(start 277.55215 -7.79526)
						(mid 277.512164 -7.9898)
						(end 277.39848 -8.152638)
					)
				)
			)
		)
	)
	(footprint ""
		(layer "F.Cu")
		(at 310.308752 -26.126694 180)
		(property "Reference" "R53"
			(at 6.826504 1.50876 0)
			(unlocked yes)
			(layer "F.SilkS")
			(effects
				(font
					(size 0.7874 0.5842)
					(thickness 0.1524)
				)
				(justify left)
			)
		)
		(property "Value" ""
			(at 0 0 180)
			(layer "F.Fab")
			(effects
				(font
					(size 1.27 1.27)
				)
			)
		)
		(duplicate_pad_numbers_are_jumpers no)
		(fp_line
			(start 0.7874 0.4064)
			(end -0.7874 0.4064)
			(stroke
				(width 0.1524)
				(type default)
			)
			(layer "F.SilkS")
		)
		(fp_line
			(start 0.7874 -0.4064)
			(end 0.7874 0.4064)
			(stroke
				(width 0.1524)
				(type default)
			)
			(layer "F.SilkS")
		)
		(fp_line
			(start -0.7874 0.4064)
			(end -0.7874 -0.4064)
			(stroke
				(width 0.1524)
				(type default)
			)
			(layer "F.SilkS")
		)
		(fp_line
			(start -0.7874 -0.4064)
			(end 0.7874 -0.4064)
			(stroke
				(width 0.1524)
				(type default)
			)
			(layer "F.SilkS")
		)
		(fp_poly
			(pts
				(xy -0.508 0.2794) (xy -0.508 0.2286) (xy -0.635 0.2286) (xy -0.635 -0.254) (xy -0.5334 -0.254)
				(xy -0.5334 -0.2794) (xy 0.5334 -0.2794) (xy 0.5334 -0.254) (xy 0.635 -0.254) (xy 0.635 0.254) (xy 0.5334 0.254)
				(xy 0.5334 0.2794)
			)
			(stroke
				(width 0)
				(type default)
			)
			(fill no)
			(layer "F.CrtYd")
		)
		(pad "1" smd rect
			(at 0.40005 0 180)
			(size 0.4572 0.508)
			(layers "F.Cu" "F.Mask" "F.Paste")
			(net "GND")
		)
		(pad "2" smd rect
			(at -0.40005 0 180)
			(size 0.4572 0.508)
			(layers "F.Cu" "F.Mask" "F.Paste")
			(net "ENET10G_4_RS1")
		)
	)
	(footprint ""
		(layer "F.Cu")
		(at 376.460004 -10.6299)
		(property "Reference" "J6"
			(at -1.0414 -11.166348 0)
			(unlocked yes)
			(layer "F.SilkS")
			(effects
				(font
					(size 0.7874 0.5842)
					(thickness 0.1524)
				)
				(justify left)
			)
		)
		(property "Value" ""
			(at 0 0 0)
			(layer "F.Fab")
			(effects
				(font
					(size 1.27 1.27)
				)
			)
		)
		(duplicate_pad_numbers_are_jumpers no)
		(fp_line
			(start -5.32511 -10.500106)
			(end -5.32511 0)
			(stroke
				(width 0.1524)
				(type default)
			)
			(layer "F.SilkS")
		)
		(fp_line
			(start -5.32511 0)
			(end -5.32511 43.029886)
			(stroke
				(width 0.1524)
				(type default)
			)
			(layer "F.SilkS")
		)
		(fp_line
			(start -5.32511 13.129768)
			(end 5.32511 13.129768)
			(stroke
				(width 0.1524)
				(type default)
			)
			(layer "F.SilkS")
		)
		(fp_line
			(start -5.32511 43.029886)
			(end 5.32511 43.029886)
			(stroke
				(width 0.1524)
				(type default)
			)
			(layer "F.SilkS")
		)
		(fp_line
			(start 5.32511 -10.500106)
			(end -5.32511 -10.500106)
			(stroke
				(width 0.1524)
				(type default)
			)
			(layer "F.SilkS")
		)
		(fp_line
			(start 5.32511 43.029886)
			(end 5.32511 -10.500106)
			(stroke
				(width 0.1524)
				(type default)
			)
			(layer "F.SilkS")
		)
		(fp_poly
			(pts
				(xy -7.80669 4.393438) (xy -6.53161 5.668772) (xy -6.523228 5.6769) (xy -5.956808 3.764788)
			)
			(stroke
				(width 0)
				(type default)
			)
			(fill yes)
			(layer "F.SilkS")
		)
		(fp_poly
			(pts
				(arc
					(start 2.758694 0)
					(mid -2.758694 0)
					(end 2.758694 0)
				)
			)
			(stroke
				(width 0)
				(type default)
			)
			(fill no)
			(layer "B.CrtYd")
		)
		(fp_poly
			(pts
				(arc
					(start 2.758694 5.62991)
					(mid -2.758694 5.62991)
					(end 2.758694 5.62991)
				)
			)
			(stroke
				(width 0)
				(type default)
			)
			(fill no)
			(layer "B.CrtYd")
		)
		(fp_poly
			(pts
				(arc
					(start 2.95275 -6.620002)
					(mid -2.95275 -6.620002)
					(end 2.95275 -6.620002)
				)
			)
			(stroke
				(width 0)
				(type default)
			)
			(fill no)
			(layer "B.CrtYd")
		)
		(fp_poly
			(pts
				(xy -5.32511 0) (xy -5.32511 43.029886) (xy 5.32511 43.029886) (xy 5.32511 -10.500106) (xy -5.32511 -10.500106)
			)
			(stroke
				(width 0)
				(type default)
			)
			(fill no)
			(layer "F.CrtYd")
		)
		(fp_line
			(start -5.32511 -10.500106)
			(end -5.32511 0)
			(stroke
				(width 0.1)
				(type default)
			)
			(layer "F.Fab")
		)
		(fp_line
			(start -5.32511 0)
			(end -5.32511 43.029886)
			(stroke
				(width 0.1)
				(type default)
			)
			(layer "F.Fab")
		)
		(fp_line
			(start -5.32511 13.129768)
			(end 5.32511 13.129768)
			(stroke
				(width 0.1)
				(type default)
			)
			(layer "F.Fab")
		)
		(fp_line
			(start -5.32511 43.029886)
			(end 5.32511 43.029886)
			(stroke
				(width 0.1)
				(type default)
			)
			(layer "F.Fab")
		)
		(fp_line
			(start 5.32511 -10.500106)
			(end -5.32511 -10.500106)
			(stroke
				(width 0.1)
				(type default)
			)
			(layer "F.Fab")
		)
		(fp_line
			(start 5.32511 43.029886)
			(end 5.32511 -10.500106)
			(stroke
				(width 0.1)
				(type default)
			)
			(layer "F.Fab")
		)
		(fp_poly
			(pts
				(xy -7.86638 -0.8636) (xy -7.86638 0.9398) (xy -7.86638 0.951484) (xy -6.11378 0)
			)
			(stroke
				(width 0)
				(type default)
			)
			(fill yes)
			(layer "F.Fab")
		)
		(fp_text user "1"
			(at -6.082284 3.796284 0)
			(unlocked yes)
			(layer "F.SilkS")
			(effects
				(font
					(size 0.7874 0.5842)
					(thickness 0.1524)
				)
				(justify left)
			)
		)
		(fp_text user "1"
			(at -2.9464 0.043688 0)
			(unlocked yes)
			(layer "B.SilkS")
			(effects
				(font
					(size 0.7874 0.5842)
					(thickness 0.1524)
				)
				(justify left mirror)
			)
		)
		(fp_text user "1"
			(at -2.9464 0.043688 0)
			(unlocked yes)
			(layer "B.Fab")
			(effects
				(font
					(size 0.7874 0.5842)
					(thickness 0.000001)
				)
				(justify left mirror)
			)
		)
		(fp_text user "1"
			(at -6.031484 -0.039116 0)
			(unlocked yes)
			(layer "F.Fab")
			(effects
				(font
					(size 0.7874 0.5842)
					(thickness 0.000001)
				)
				(justify left)
			)
		)
		(pad "1" thru_hole circle
			(at 0 0)
			(size 5.4102 5.4102)
			(drill 4.0132)
			(layers "*.Cu" "*.Mask")
			(remove_unused_layers no)
			(net "GND")
			(clearance -0.4445)
		)
		(pad "2" thru_hole circle
			(at 0 5.62991)
			(size 5.4102 5.4102)
			(drill 4.0132)
			(layers "*.Cu" "*.Mask")
			(remove_unused_layers no)
			(net "GND")
			(clearance -0.4445)
		)
		(pad "3" thru_hole circle
			(at 0 -6.620002)
			(size 5.7912 5.7912)
			(drill 4.0132)
			(layers "*.Cu" "*.Mask")
			(remove_unused_layers no)
			(net "GND")
			(clearance -0.635)
		)
	)
)
